FILE_TYPE = CONNECTIVITY;
{Allegro Design Entry HDL 17.4-2019 S026 (4007227) 1/17/2022}
"PAGE_NUMBER" = 185;
0"NC";
1"GND\g";
2"GND\g";
3"GND\g";
4"GND\g";
5"GND\g";
6"GND\g";
7"GND\g";
8"GND\g";
9"GND\g";
10"GND\g";
11"GND\g";
12"PVDDCR_SOC_P1\g";
13"GND\g";
14"GND\g";
15"GND\g";
16"GND\g";
17"GND\g";
18"GND\g";
19"GND\g";
20"GND\g";
21"PVDDCR_CPU0_P1\g";
22"GND\g";
23"GND\g";
24"VSENSE_VSS_SENSE_A_P1";
25"PVDDCR_CPU0_P1_PWM4";
26"PVDDCR_CPU0_P1_IMON4";
27"GND\g";
28"GND\g";
29"GND\g";
30"PVDD18_S5_P1\g";
31"GND\g"VOLTAGE"0";
32"P3V3_AUX\g";
33"P5V_AUX\g";
34"P12V_AUX\g";
35"GND\g";
36"P3V3_AUX\g";
37"PVDD18_S5_P1\g";
38"P3V3_AUX\g";
39"PVDD18_S5_P1\g";
40"GND\g";
41"GND\g";
42"P3V3_AUX\g";
43"GND\g";
44"GND\g";
45"SMB_VR_3V3STBY_SDA";
46"PVDDCR_CPU0_P1_IMON1";
47"PVDDCR_CPU0_P1_VCC";
48"SVID_PVDDCR_CPU0_P1_SVTI_R";
49"PVDDCR_CPU0_P1_PMSCL_R";
50"SVID_PVDDCR_CPU0_P1_SVC_R1";
51"PVDDCR_CPU0_P1_IMON6";
52"SVID_PVDDCR_CPU0_P1_SVTO_R";
53"PVDDCR_CPU0_P1_RESET_N_R";
54"NC_PVDDCR_CPU0_P1_IMON7";
55"NC_PVDDCR_CPU0_P1_IMON8";
56"PWRGD_PVDDCR_SOC_P1_R";
57"SVID_PVDDCR_CPU0_P1_SVD_R1";
58"PVDDCR_CPU0_P1_PMALERT_R";
59"PVDDCR_CPU0_P1_EN_R";
60"PVDDCR_CPU0_P1_PMSDA_R";
61"NC_PVDDCR_CPU0_P1_PWM8";
62"NC_PVDDCR_CPU0_P1_PWM7";
63"VSENSE_PVDDCR_CPU0_P1_VSEN0";
64"PVDDCR_SOC_P1_PWM2";
65"PWRGD_PVDDCR_CPU0_P1_R";
66"PVDDCR_CPU0_P1_PWM6";
67"PVDDCR_CPU0_P1_VCCS";
68"PVDDCR_CPU0_P1_VMON";
69"PVDDCR_CPU0_P1_VINSEN";
70"PVDDCR_CPU0_P1_TEMP0";
71"VSENSE_PVDDCR_SOC_P1_VSEN1";
72"VSENSE_VSS_SENSE_A_P1";
73"PVDDCR_SOC_P1_IMON2";
74"PVDDCR_CPU0_P1_PWM1";
75"NC_PVDDCR_CPU0_P1_PWM9";
76"NC_PVDDCR_CPU0_P1_IMON9";
77"PVDDCR_SOC_P1_PWM3";
78"PVDDCR_SOC_P1_IMON3";
79"PVDDCR_CPU0_P1_OCP_N_R";
80"PVDDCR_SOC_P1_EN//ADDR_CFG";
81"PVDDCR_SOC_P1_TEMP1";
82"PVDDCR_SOC_P1_PWM1";
83"PVDDCR_SOC_P1_IMON1";
84"PVDDCR_CPU0_P1_PWM5";
85"PVDDCR_CPU0_P1_IMON5";
86"PVDDCR_CPU0_P1_PWM3";
87"PVDDCR_CPU0_P1_IMON3";
88"PVDDCR_CPU0_P1_PWM2";
89"PVDDCR_CPU0_P1_IMON2";
90"SVID_PVDDCR_CPU0_P1_SVTO";
91"PVDDCR_CPU0_P1_EN";
92"SVID_PVDDCR_CPU0_P1_SVD_R";
93"SVID_PVDDCR_CPU0_P1_SVC_R";
94"PWRGD_PVDDCR_CPU0_P1";
95"SVID_PVDDCR_CPU0_P1_SVTI";
96"VSENSE_PVDDCR_SOC_P1_DP";
97"PVDDCR_CPU0_P1_RESET_N";
98"PVDDCR_SOC_P1_EN_RC";
99"PVDDCR_SOC_P1_EN_GD";
100"PVDDCR_CPU0_P1_PMALERT";
101"SMB_VR_3V3STBY_SCL";
102"PVDDCR_SOC_P1_EN";
103"PWRGD_PVDDCR_SOC_P1";
104"VSENSE_PVDDCR_CPU0_P1_DP";
105"PVDDCR_CPU0_P1_OCP_N";
%"Q_RES"
"2","(-5125,7750)","0","pure_quanta","I10";
;
LOCATION"PR151"
$SEC"1"
CDS_SEC"1"
MATERIAL"EMPTY"
WATTAGE"1/16W"
VALUE"1K"
TOLERANCE"1%"
PACK_TYPE"0402LF"
CDS_LIB"pure_quanta"
PART_NUMBER"CS21002FB06";
"A"
$PN"1"30;
"B"
$PN"2"95;
%"Q_RES"
"1","(400,4375)","0","pure_quanta","I102";
;
LOCATION"PR437"
$SEC"1"
CDS_SEC"1"
PACK_TYPE"0402LF"
VALUE"0"
TOLERANCE"5%"
MATERIAL"CHIP"
WATTAGE"1/16W"
CDS_LIB"pure_quanta"
PART_NUMBER"CS00002JB13";
"B"
$PN"2"27;
"A"
$PN"1"76;
%"Q_RES"
"1","(400,4675)","0","pure_quanta","I103";
;
LOCATION"PR436"
$SEC"1"
CDS_SEC"1"
VALUE"0"
MATERIAL"CHIP"
WATTAGE"1/16W"
PACK_TYPE"0402LF"
TOLERANCE"5%"
CDS_LIB"pure_quanta"
PART_NUMBER"CS00002JB13";
"B"
$PN"2"28;
"A"
$PN"1"55;
%"UNIVERSAL_GND"
"1","(725,4250)","0","pure_quanta_power","I104";
;
CDS_LIB"pure_quanta_power"
HDL_POWER"GND";
"A"27;
%"UNIVERSAL_GND"
"1","(725,4550)","0","pure_quanta_power","I105";
;
CDS_LIB"pure_quanta_power"
HDL_POWER"GND";
"A"28;
%"UNIVERSAL_GND"
"1","(725,4850)","0","pure_quanta_power","I106";
;
CDS_LIB"pure_quanta_power"
HDL_POWER"GND";
"A"29;
%"Q_RES"
"1","(400,4975)","0","pure_quanta","I107";
;
LOCATION"PR530"
$SEC"1"
CDS_SEC"1"
TOLERANCE"5%"
MATERIAL"CHIP"
WATTAGE"1/16W"
VALUE"0"
PACK_TYPE"0402LF"
CDS_LIB"pure_quanta"
PART_NUMBER"CS00002JB13";
"B"
$PN"2"29;
"A"
$PN"1"54;
%"VCC_CORE"
"1","(-5125,8050)","0","pure_quanta_power","I11";
;
HDL_POWER"PVDD18_S5_P1"
CDS_LIB"pure_quanta_power";
"A"30;
%"UNIVERSAL_GND"
"1","(-25,7200)","0","pure_quanta_power","I113";
;
CDS_LIB"pure_quanta_power"
HDL_POWER"GND";
"A"1;
%"Q_CAP"
"1","(-25,7425)","0","pure_quanta","I114";
;
LOCATION"PC11"
$SEC"1"
CDS_SEC"1"
PACK_TYPE"0402"
MATERIAL"X7R"
TOLERANCE"10%"
VALUE"0.1UF"
VOLTAGE"25V"
CDS_LIB"pure_quanta"
PART_NUMBER"CH4104K1B00";
"B"
$PN"2"1;
"A"
$PN"1"67;
%"UNIVERSAL_GND"
"1","(-25,7650)","0","pure_quanta_power","I115";
;
CDS_LIB"pure_quanta_power"
HDL_POWER"GND";
"A"2;
%"Q_CAP"
"1","(-25,7900)","0","pure_quanta","I116";
;
LOCATION"PC10"
$SEC"1"
CDS_SEC"1"
MATERIAL"X7R"
TOLERANCE"10%"
VOLTAGE"25V"
PACK_TYPE"0402"
VALUE"0.1UF"
CDS_LIB"pure_quanta"
PART_NUMBER"CH4104K1B00";
"B"
$PN"2"2;
"A"
$PN"1"47;
%"UNIVERSAL_GND"
"1","(-4850,2725)","0","pure_quanta_power","I12";
;
CDS_LIB"pure_quanta_power"
HDL_POWER"GND";
"A"31;
%"UNIVERSAL_GND"
"1","(300,7200)","0","pure_quanta_power","I124";
;
CDS_LIB"pure_quanta_power"
HDL_POWER"GND";
"A"3;
%"Q_CAP"
"1","(300,7425)","0","pure_quanta","I125";
;
LOCATION"PC251"
$SEC"1"
CDS_SEC"1"
PACK_TYPE"C0402"
VOLTAGE"6.3V"
VALUE"10UF"
TOLERANCE"20%"
MATERIAL"X6S"
CDS_LIB"pure_quanta"
PART_NUMBER"CH6101MEB03";
"B"
$PN"2"3;
"A"
$PN"1"67;
%"UNIVERSAL_GND"
"1","(325,7650)","0","pure_quanta_power","I126";
;
CDS_LIB"pure_quanta_power"
HDL_POWER"GND";
"A"4;
%"Q_CAP"
"1","(325,7900)","0","pure_quanta","I127";
;
LOCATION"PC252"
$SEC"1"
CDS_SEC"1"
TOLERANCE"10%"
VALUE"1UF"
PACK_TYPE"C0402"
MATERIAL"X6S"
VOLTAGE"16V"
CDS_LIB"pure_quanta"
PART_NUMBER"CH5103KEB01";
"B"
$PN"2"4;
"A"
$PN"1"47;
%"Q_RES"
"1","(750,8050)","0","pure_quanta","I129";
;
LOCATION"PR183"
$SEC"1"
CDS_SEC"1"
PACK_TYPE"0402LF"
VALUE"1"
TOLERANCE"1%"
MATERIAL"CHIP"
WATTAGE"1/16W"
CDS_LIB"pure_quanta"
PART_NUMBER"CS-1002FB04";
"B"
$PN"2"32;
"A"
$PN"1"47;
%"Q_CAP"
"1","(-4850,2950)","0","pure_quanta","I13";
;
LOCATION"C242"
$SEC"1"
CDS_SEC"1"
VOLTAGE"50V"
PACK_TYPE"0402"
VALUE"1000PF"
TOLERANCE"5%"
MATERIAL"X7R"
CDS_LIB"pure_quanta"
PART_NUMBER"TMP_QCH21006JB10";
"B"
$PN"2"31;
"A"
$PN"1"98;
%"VCC_CORE"
"1","(1175,8150)","0","pure_quanta_power","I130";
;
HDL_POWER"P3V3_AUX"
CDS_LIB"pure_quanta_power";
"A"32;
%"VCC_CORE"
"1","(-4325,2725)","0","pure_quanta_power","I131";
;
HDL_POWER"P5V_AUX"
CDS_LIB"pure_quanta_power";
"A"33;
%"Q_CAP"
"2","(-2450,3500)","0","pure_quanta","I132";
;
LOCATION"PC247"
$SEC"1"
CDS_SEC"1"
PACK_TYPE"0402"
VOLTAGE"6.3V"
MATERIAL"X7R"
TOLERANCE"10%"
VALUE"1UF"
CDS_LIB"pure_quanta"
PART_NUMBER"CH5101K1B01";
"A"
$PN"1"37;
"B"
$PN"2"17;
%"RAA229620GNPHA0"
"1","(-1075,5125)","0","pure_quanta","I133";
;
LOCATION"PU25"
SEC"1"
MATERIAL"IC"
PART_TYPE"SMLF"
VALUE"RAA229620GNP#HA0"
CDS_LIB"pure_quanta"
NEEDS_NO_SIZE"TRUE"
CDS_LMAN_SYM_OUTLINE"-550,2850,500,-2850"
SEC_TYPE""
PART_NUMBER"ARF0TGP4002";
"CS10"
$PN"28"89;
"PWM10"
$PN"11"88;
"CS9"
$PN"29"87;
"PWM9"
$PN"10"86;
"CS8"
$PN"30"26;
"PWM8"
$PN"9"25;
"CS7"
$PN"31"85;
"PWM7"
$PN"8"84;
"CS0"
$PN"38"83;
"PWM0"
$PN"1"82;
"TEMP1"
$PN"43"81;
"EN1||ADDR_CFG"
$PN"42"80;
"TH_GND"
$PN"TH"41;
"OCP_L \B"
$PN"41"79;
"CS2"
$PN"36"78;
"PWM2"
$PN"3"77;
"CS3"
$PN"35"76;
"PWM3"
$PN"4"75;
"PWM11"
$PN"12"74;
"CS1"
$PN"37"73;
"RGND1"
$PN"39"72;
"VSEN1"
$PN"40"71;
"VDDIO"
$PN"19"37;
"TEMP0"
$PN"44"70;
"VINSEN"
$PN"46"69;
"VMON||IINSEN"
$PN"45"68;
"VCCS"
$PN"48"67;
"PWM6"
$PN"7"66;
"PG0"
$PN"16"65;
"PWM1"
$PN"2"64;
"VSEN0"
$PN"25"63;
"PWM5"
$PN"6"62;
"PWM4"
$PN"5"61;
"PMSDA"
$PN"13"60;
"RGND0"
$PN"26"24;
"EN0"
$PN"17"59;
"NPMALERT \B"
$PN"15"58;
"SVD"
$PN"21"57;
"PG1"
$PN"20"56;
"CS4"
$PN"34"55;
"CS5"
$PN"33"54;
"RESET_L \B"
$PN"18"53;
"SVTO"
$PN"23"52;
"CS6"
$PN"32"51;
"SVC"
$PN"22"50;
"PMSCL"
$PN"14"49;
"SVTI"
$PN"24"48;
"VCC"
$PN"47"47;
"CS11"
$PN"27"46;
%"Q_RES"
"2","(-5075,2950)","0","pure_quanta","I135";
;
LOCATION"R6087"
$SEC"1"
CDS_SEC"1"
VALUE"10K"
PACK_TYPE"0402LF"
WATTAGE"1/16W"
TOLERANCE"1%"
MATERIAL"EMPTY"
CDS_LIB"pure_quanta"
PART_NUMBER"CS31002FB08";
"A"
$PN"1"98;
"B"
$PN"2"31;
%"UNIVERSAL_GND"
"1","(-4200,2900)","7","pure_quanta_power","I136";
;
CDS_LIB"pure_quanta_power"
HDL_POWER"GND";
"A"5;
%"Q_CAP"
"2","(-3900,2900)","0","pure_quanta","I137";
;
LOCATION"C5019"
$SEC"1"
CDS_SEC"1"
MATERIAL"X7R"
VOLTAGE"50V"
VALUE"1000PF"
PACK_TYPE"0402"
TOLERANCE"5%"
CDS_LIB"pure_quanta"
PART_NUMBER"TMP_QCH21006JB10";
"A"
$PN"1"5;
"B"
$PN"2"103;
%"UNIVERSAL_GND"
"1","(-3125,6050)","0","pure_quanta_power","I138";
;
CDS_LIB"pure_quanta_power"
HDL_POWER"GND";
"A"6;
%"Q_CAP"
"1","(-3125,6250)","0","pure_quanta","I139";
;
LOCATION"C5012"
$SEC"1"
CDS_SEC"1"
VALUE"1000PF"
VOLTAGE"50V"
TOLERANCE"5%"
MATERIAL"X7R"
PACK_TYPE"0402"
CDS_LIB"pure_quanta"
PART_NUMBER"TMP_QCH21006JB10";
"B"
$PN"2"6;
"A"
$PN"1"100;
%"Q_RES"
"1","(-4025,2600)","0","pure_quanta","I14";
;
LOCATION"PR157"
$SEC"1"
CDS_SEC"1"
VALUE"40.2K"
TOLERANCE"1%"
MATERIAL"CHIP"
WATTAGE"1/16W"
PACK_TYPE"0402LF"
CDS_LIB"pure_quanta"
PART_NUMBER"CS34022FB04";
"B"
$PN"2"68;
"A"
$PN"1"33;
%"UNIVERSAL_GND"
"1","(-3900,7950)","7","pure_quanta_power","I140";
;
CDS_LIB"pure_quanta_power"
HDL_POWER"GND";
"A"7;
%"Q_CAP"
"2","(-3600,7950)","0","pure_quanta","I141";
;
LOCATION"C5003"
$SEC"1"
CDS_SEC"1"
VALUE"1000PF"
VOLTAGE"50V"
TOLERANCE"5%"
MATERIAL"X7R"
PACK_TYPE"0402"
CDS_LIB"pure_quanta"
PART_NUMBER"TMP_QCH21006JB10";
"A"
$PN"1"7;
"B"
$PN"2"94;
%"Q_RES"
"2","(-3875,3150)","0","pure_quanta","I142";
;
LOCATION"PR159"
$SEC"1"
CDS_SEC"1"
PACK_TYPE"0402LF"
MATERIAL"CHIP"
WATTAGE"1/16W"
TOLERANCE"1%"
VALUE"5.23K"
CDS_LIB"pure_quanta"
PART_NUMBER"CS25232FB08";
"A"
$PN"1"80;
"B"
$PN"2"35;
%"Q_RES"
"1","(-2800,7425)","0","pure_quanta","I143";
;
LOCATION"PR8009"
$SEC"1"
CDS_SEC"1"
WATTAGE"1/16W"
PACK_TYPE"0402LF"
VALUE"0"
MATERIAL"CHIP"
TOLERANCE"5%"
CDS_LIB"pure_quanta"
PART_NUMBER"CS00002JB13";
"B"
$PN"2"50;
"A"
$PN"1"93;
%"Q_RES"
"1","(-2800,7275)","0","pure_quanta","I144";
;
LOCATION"PR8010"
$SEC"1"
CDS_SEC"1"
VALUE"0"
WATTAGE"1/16W"
MATERIAL"CHIP"
TOLERANCE"5%"
PACK_TYPE"0402LF"
CDS_LIB"pure_quanta"
PART_NUMBER"CS00002JB13";
"B"
$PN"2"57;
"A"
$PN"1"92;
%"MOSFET_N"
"1","(-4600,3300)","0","pure_quanta","I16";
;
LOCATION"PQ15"
$SEC"1"
CDS_SEC"1"
MATERIAL"IC"
VALUE"BSS138K"
MANUF_PN"BSS138K"
CDS_LMAN_SYM_OUTLINE"-50,50,100,-150"
CDS_LIB"pure_quanta"
PACK_TYPE"SMLF"
PART_NUMBER"BAM138K0000";
"GATE"
$PN"G"98;
"SOURCE"
$PN"S"35;
"DRAIN"
$PN"D"99;
%"Q_RES"
"2","(-4550,3850)","0","pure_quanta","I17";
;
LOCATION"PR152"
$SEC"1"
CDS_SEC"1"
PACK_TYPE"0402LF"
VALUE"1K"
TOLERANCE"1%"
MATERIAL"CHIP"
WATTAGE"1/16W"
CDS_LIB"pure_quanta"
PART_NUMBER"CS21002FB06";
"A"
$PN"1"38;
"B"
$PN"2"99;
%"MOSFET_PCH_GDS_ESD_PROTECTED"
"1","(-3900,3625)","6","pure_quanta","I18";
;
LOCATION"PQ11"
$SEC"1"
CDS_SEC"1"
VALUE"PJA3415AE"
MATERIAL"IC"
CDS_LIB"pure_quanta"
CDS_LMAN_SYM_OUTLINE"-125,150,125,-150"
NEEDS_NO_SIZE"TRUE"
PART_TYPE"SMLF"
PART_NUMBER"BAM34150008";
"S"
$PN"S"38;
"G"
$PN"G"99;
"D"
$PN"D"80;
%"UNIVERSAL_GND"
"1","(-3725,2175)","0","pure_quanta_power","I19";
;
CDS_LIB"pure_quanta_power"
HDL_POWER"GND";
"A"8;
%"Q_RES"
"1","(-5375,3200)","0","pure_quanta","I2";
;
LOCATION"R149"
$SEC"1"
CDS_SEC"1"
MATERIAL"CHIP"
VALUE"0"
TOLERANCE"5%"
WATTAGE"1/16W"
PACK_TYPE"0402LF"
CDS_LIB"pure_quanta"
PART_NUMBER"CS00002JB13";
"B"
$PN"2"98;
"A"
$PN"1"102;
%"Q_RES"
"2","(-3725,2425)","0","pure_quanta","I20";
;
LOCATION"PR4"
SEC"1"
PACK_TYPE"0402LF"
VALUE"10K"
TOLERANCE"1%"
WATTAGE"1/16W"
MATERIAL"CHIP"
CDS_LIB"pure_quanta"
SEC_TYPE"0402LF"
PART_NUMBER"CS31002FB08";
"A"
$PN"1"68;
"B"
$PN"2"8;
%"UNIVERSAL_GND"
"1","(-3250,2175)","0","pure_quanta_power","I21";
;
CDS_LIB"pure_quanta_power"
HDL_POWER"GND";
"A"9;
%"Q_CAP"
"1","(-3250,2425)","0","pure_quanta","I22";
;
LOCATION"PC243"
$SEC"1"
CDS_SEC"1"
MATERIAL"X7R"
PACK_TYPE"0402"
TOLERANCE"10%"
VOLTAGE"25V"
VALUE"0.1UF"
CDS_LIB"pure_quanta"
PART_NUMBER"CH4104K1B00";
"B"
$PN"2"9;
"A"
$PN"1"68;
%"Q_RES"
"1","(-3100,2775)","0","pure_quanta","I23";
;
LOCATION"R8166"
$SEC"1"
CDS_SEC"1"
TOLERANCE"5%"
PACK_TYPE"0402LF"
WATTAGE"1/16W"
MATERIAL"CHIP"
VALUE"33"
CDS_LIB"pure_quanta"
PART_NUMBER"CS03302JB10";
"B"
$PN"2"56;
"A"
$PN"1"103;
%"VCC_CORE"
"1","(-2975,2500)","0","pure_quanta_power","I24";
;
HDL_POWER"P12V_AUX"
CDS_LIB"pure_quanta_power";
"A"34;
%"UNIVERSAL_GND"
"1","(-3875,2950)","0","pure_quanta_power","I25";
;
CDS_LIB"pure_quanta_power"
HDL_POWER"GND";
"A"35;
%"Q_RES"
"1","(-3100,3025)","0","pure_quanta","I27";
;
LOCATION"R8165"
$SEC"1"
CDS_SEC"1"
WATTAGE"1/16W"
PACK_TYPE"0402LF"
VALUE"1K"
TOLERANCE"1%"
MATERIAL"CHIP"
CDS_LIB"pure_quanta"
PART_NUMBER"CS21002FB06";
"B"
$PN"2"56;
"A"
$PN"1"36;
%"VCC_CORE"
"1","(-3375,3175)","0","pure_quanta_power","I28";
;
HDL_POWER"P3V3_AUX"
CDS_LIB"pure_quanta_power";
"A"36;
%"VCC_CORE"
"1","(-3000,3575)","0","pure_quanta_power","I29";
;
HDL_POWER"PVDD18_S5_P1"
CDS_LIB"pure_quanta_power";
"A"37;
%"UNIVERSAL_GND"
"1","(-5300,6550)","0","pure_quanta_power","I3";
;
CDS_LIB"pure_quanta_power"
HDL_POWER"GND";
"A"10;
%"VCC_CORE"
"1","(-4550,4075)","0","pure_quanta_power","I30";
;
HDL_POWER"P3V3_AUX"
CDS_LIB"pure_quanta_power";
"A"38;
%"UNIVERSAL_GND"
"1","(-3875,4100)","0","pure_quanta_power","I35";
;
CDS_LIB"pure_quanta_power"
HDL_POWER"GND";
"A"11;
%"Q_RES"
"2","(-3875,4300)","0","pure_quanta","I36";
;
LOCATION"PR164"
$SEC"1"
CDS_SEC"1"
WATTAGE"1/16W"
MATERIAL"CHIP"
PACK_TYPE"0402LF"
TOLERANCE"1%"
VALUE"49.9"
CDS_LIB"pure_quanta"
PART_NUMBER"CS04992FB07";
"A"
$PN"1"72;
"B"
$PN"2"11;
%"Q_RES"
"2","(-3875,4900)","0","pure_quanta","I39";
;
LOCATION"PR163"
$SEC"1"
CDS_SEC"1"
TOLERANCE"1%"
VALUE"49.9"
PACK_TYPE"0402LF"
MATERIAL"CHIP"
WATTAGE"1/16W"
CDS_LIB"pure_quanta"
PART_NUMBER"CS04992FB07";
"A"
$PN"1"12;
"B"
$PN"2"96;
%"Q_RES"
"2","(-5300,6800)","0","pure_quanta","I4";
;
LOCATION"PR150"
$SEC"1"
CDS_SEC"1"
PACK_TYPE"0402LF"
MATERIAL"CHIP"
WATTAGE"1/16W"
VALUE"0"
TOLERANCE"5%"
CDS_LIB"pure_quanta"
PART_NUMBER"CS00002JB13";
"A"
$PN"1"95;
"B"
$PN"2"10;
%"VCC_CORE"
"1","(-3300,4300)","0","pure_quanta_power","I40";
;
HDL_POWER"PVDD18_S5_P1"
CDS_LIB"pure_quanta_power";
"A"39;
%"Q_RES"
"1","(-2850,4175)","0","pure_quanta","I41";
;
LOCATION"R8184"
$SEC"1"
CDS_SEC"1"
TOLERANCE"1%"
VALUE"1K"
WATTAGE"1/16W"
MATERIAL"CHIP"
PACK_TYPE"0402LF"
CDS_LIB"pure_quanta"
PART_NUMBER"CS21002FB06";
"B"
$PN"2"53;
"A"
$PN"1"39;
%"Q_RES"
"1","(-2825,4025)","0","pure_quanta","I42";
;
LOCATION"R8182"
$SEC"1"
CDS_SEC"1"
MATERIAL"CHIP"
WATTAGE"1/16W"
PACK_TYPE"0402LF"
TOLERANCE"1%"
VALUE"49.9"
CDS_LIB"pure_quanta"
PART_NUMBER"CS04992FB07";
"B"
$PN"2"53;
"A"
$PN"1"97;
%"Q_RES"
"1","(-2825,3875)","0","pure_quanta","I43";
;
LOCATION"R8168"
$SEC"1"
CDS_SEC"1"
PACK_TYPE"0402LF"
MATERIAL"CHIP"
TOLERANCE"5%"
VALUE"0"
WATTAGE"1/16W"
CDS_LIB"pure_quanta"
PART_NUMBER"CS00002JB13";
"B"
$PN"2"79;
"A"
$PN"1"105;
%"VCC_CORE"
"1","(-3875,5075)","0","pure_quanta_power","I44";
;
HDL_POWER"PVDDCR_SOC_P1"
CDS_LIB"pure_quanta_power";
"A"12;
%"Q_RES"
"2","(-3875,5400)","0","pure_quanta","I45";
;
LOCATION"PR162"
$SEC"1"
CDS_SEC"1"
TOLERANCE"1%"
PACK_TYPE"0402LF"
VALUE"49.9"
MATERIAL"CHIP"
WATTAGE"1/16W"
CDS_LIB"pure_quanta"
PART_NUMBER"CS04992FB07";
"A"
$PN"1"24;
"B"
$PN"2"13;
%"UNIVERSAL_GND"
"1","(-3875,5200)","0","pure_quanta_power","I46";
;
CDS_LIB"pure_quanta_power"
HDL_POWER"GND";
"A"13;
%"Q_RES"
"1","(-2725,2425)","0","pure_quanta","I47";
;
LOCATION"PR181"
$SEC"1"
CDS_SEC"1"
MATERIAL"CHIP"
PACK_TYPE"0402LF"
VALUE"0"
TOLERANCE"5%"
WATTAGE"1/16W"
CDS_LIB"pure_quanta"
PART_NUMBER"CS00002JB13";
"B"
$PN"2"69;
"A"
$PN"1"34;
%"Q_RES"
"2","(-2400,2225)","0","pure_quanta","I48";
;
LOCATION"PR602"
$SEC"1"
CDS_SEC"1"
PACK_TYPE"0402LF"
VALUE"4.99K"
TOLERANCE"1%"
MATERIAL"EMPTY"
WATTAGE"1/16W"
CDS_LIB"pure_quanta"
PART_NUMBER"CS24992FB07";
"A"
$PN"1"69;
"B"
$PN"2"14;
%"UNIVERSAL_GND"
"1","(-2400,2025)","0","pure_quanta_power","I49";
;
CDS_LIB"pure_quanta_power"
HDL_POWER"GND";
"A"14;
%"UNIVERSAL_GND"
"1","(-5025,6550)","0","pure_quanta_power","I5";
;
CDS_LIB"pure_quanta_power"
HDL_POWER"GND";
"A"15;
%"UNIVERSAL_GND"
"1","(-2075,2025)","0","pure_quanta_power","I50";
;
CDS_LIB"pure_quanta_power"
HDL_POWER"GND";
"A"16;
%"Q_CAP"
"1","(-2075,2250)","0","pure_quanta","I51";
;
LOCATION"PC6"
SEC"1"
MATERIAL"X7R"
TOLERANCE"10%"
VALUE"0.1UF"
VOLTAGE"25V"
PACK_TYPE"0402"
CDS_LIB"pure_quanta"
SEC_TYPE"0402"
PART_NUMBER"CH4104K1B00";
"B"
$PN"2"16;
"A"
$PN"1"69;
%"Q_CAP"
"2","(-2425,3025)","0","pure_quanta","I52";
;
LOCATION"C8246"
$SEC"1"
CDS_SEC"1"
MATERIAL"EMPTY"
VALUE"1000PF"
VOLTAGE"50V"
PACK_TYPE"0402"
TOLERANCE"5%"
CDS_LIB"pure_quanta"
PART_NUMBER"TMP_QCH21006JB10";
"A"
$PN"1"56;
"B"
$PN"2"40;
%"UNIVERSAL_GND"
"1","(-2100,2900)","0","pure_quanta_power","I53";
;
CDS_LIB"pure_quanta_power"
HDL_POWER"GND";
"A"40;
%"Q_RES"
"1","(-2175,3750)","0","pure_quanta","I54";
;
LOCATION"R8180"
$SEC"1"
CDS_SEC"1"
MATERIAL"CHIP"
WATTAGE"1/16W"
TOLERANCE"1%"
PACK_TYPE"0402LF"
VALUE"1K"
CDS_LIB"pure_quanta"
PART_NUMBER"CS21002FB06";
"B"
$PN"2"79;
"A"
$PN"1"37;
%"UNIVERSAL_GND"
"1","(-2050,3500)","1","pure_quanta_power","I55";
;
CDS_LIB"pure_quanta_power"
HDL_POWER"GND";
"A"17;
%"UNIVERSAL_GND"
"1","(-1875,2225)","0","pure_quanta_power","I56";
;
CDS_LIB"pure_quanta_power"
HDL_POWER"GND";
"A"41;
%"Q_RES"
"1","(-2725,4725)","0","pure_quanta","I57";
;
LOCATION"PR174"
$SEC"1"
CDS_SEC"1"
PACK_TYPE"0402LF"
VALUE"0"
TOLERANCE"5%"
WATTAGE"1/16W"
MATERIAL"CHIP"
CDS_LIB"pure_quanta"
PART_NUMBER"CS00002JB13";
"B"
$PN"2"71;
"A"
$PN"1"96;
%"Q_CAP"
"1","(-2450,4600)","0","pure_quanta","I58";
;
LOCATION"PC245"
$SEC"1"
CDS_SEC"1"
PACK_TYPE"0402"
MATERIAL"X7R"
VOLTAGE"50V"
VALUE"3300PF"
TOLERANCE"10%"
CDS_LIB"pure_quanta"
PART_NUMBER"TMP_QCH2336K1B12";
"B"
$PN"2"72;
"A"
$PN"1"71;
%"Q_RES"
"1","(-2800,5825)","0","pure_quanta","I59";
;
LOCATION"PR173"
$SEC"1"
CDS_SEC"1"
TOLERANCE"5%"
VALUE"0"
PACK_TYPE"0402LF"
MATERIAL"CHIP"
WATTAGE"1/16W"
CDS_LIB"pure_quanta"
PART_NUMBER"CS00002JB13";
"B"
$PN"2"63;
"A"
$PN"1"104;
%"Q_RES"
"2","(-5025,6800)","0","pure_quanta","I6";
;
LOCATION"R8153"
$SEC"1"
CDS_SEC"1"
WATTAGE"1/16W"
PACK_TYPE"0402LF"
TOLERANCE"1%"
VALUE"1K"
MATERIAL"EMPTY"
CDS_LIB"pure_quanta"
PART_NUMBER"CS21002FB06";
"A"
$PN"1"90;
"B"
$PN"2"15;
%"Q_CAP"
"1","(-2525,5700)","0","pure_quanta","I60";
;
LOCATION"PC244"
$SEC"1"
CDS_SEC"1"
MATERIAL"X7R"
VOLTAGE"50V"
VALUE"3300PF"
TOLERANCE"10%"
PACK_TYPE"0402"
CDS_LIB"pure_quanta"
PART_NUMBER"TMP_QCH2336K1B12";
"B"
$PN"2"24;
"A"
$PN"1"63;
%"UNIVERSAL_GND"
"1","(-4825,6550)","0","pure_quanta_power","I61";
;
CDS_LIB"pure_quanta_power"
HDL_POWER"GND";
"A"18;
%"Q_CAP"
"1","(-4825,6800)","0","pure_quanta","I62";
;
LOCATION"C295"
$SEC"1"
CDS_SEC"1"
PACK_TYPE"0402"
VALUE"10PF"
TOLERANCE"5%"
VOLTAGE"50V"
MATERIAL"EMPTY"
CDS_LIB"pure_quanta"
PART_NUMBER"CH01006JB08";
"B"
$PN"2"18;
"A"
$PN"1"90;
%"UNIVERSAL_GND"
"1","(-4600,6550)","0","pure_quanta_power","I63";
;
CDS_LIB"pure_quanta_power"
HDL_POWER"GND";
"A"19;
%"Q_CAP"
"1","(-4600,6800)","0","pure_quanta","I64";
;
LOCATION"C296"
$SEC"1"
CDS_SEC"1"
MATERIAL"EMPTY"
VALUE"10PF"
TOLERANCE"5%"
VOLTAGE"50V"
PACK_TYPE"0402"
CDS_LIB"pure_quanta"
PART_NUMBER"CH01006JB08";
"B"
$PN"2"19;
"A"
$PN"1"92;
%"UNIVERSAL_GND"
"1","(-4325,6550)","0","pure_quanta_power","I65";
;
CDS_LIB"pure_quanta_power"
HDL_POWER"GND";
"A"20;
%"Q_CAP"
"1","(-4325,6800)","0","pure_quanta","I66";
;
LOCATION"C297"
$SEC"1"
CDS_SEC"1"
VALUE"10PF"
MATERIAL"EMPTY"
TOLERANCE"5%"
VOLTAGE"50V"
PACK_TYPE"0402"
CDS_LIB"pure_quanta"
PART_NUMBER"CH01006JB08";
"B"
$PN"2"20;
"A"
$PN"1"93;
%"Q_RES"
"2","(-4775,7750)","0","pure_quanta","I67";
;
LOCATION"R154"
$SEC"1"
CDS_SEC"1"
MATERIAL"EMPTY"
PACK_TYPE"0402LF"
WATTAGE"1/16W"
VALUE"1K"
TOLERANCE"1%"
CDS_LIB"pure_quanta"
PART_NUMBER"CS21002FB06";
"A"
$PN"1"30;
"B"
$PN"2"90;
%"Q_RES"
"2","(-4475,7750)","0","pure_quanta","I68";
;
LOCATION"R8156"
$SEC"1"
CDS_SEC"1"
PACK_TYPE"0402LF"
WATTAGE"1/16W"
MATERIAL"EMPTY"
TOLERANCE"1%"
VALUE"1K"
CDS_LIB"pure_quanta"
PART_NUMBER"CS21002FB06";
"A"
$PN"1"30;
"B"
$PN"2"92;
%"Q_RES"
"2","(-4200,7750)","0","pure_quanta","I69";
;
LOCATION"R8160"
$SEC"1"
CDS_SEC"1"
WATTAGE"1/16W"
MATERIAL"EMPTY"
TOLERANCE"1%"
VALUE"1K"
PACK_TYPE"0402LF"
CDS_LIB"pure_quanta"
PART_NUMBER"CS21002FB06";
"A"
$PN"1"30;
"B"
$PN"2"93;
%"Q_RES"
"2","(-3875,6025)","0","pure_quanta","I70";
;
LOCATION"PR161"
$SEC"1"
CDS_SEC"1"
VALUE"49.9"
WATTAGE"1/16W"
PACK_TYPE"0402LF"
TOLERANCE"1%"
MATERIAL"CHIP"
CDS_LIB"pure_quanta"
PART_NUMBER"CS04992FB07";
"A"
$PN"1"21;
"B"
$PN"2"104;
%"VCC_CORE"
"1","(-3875,6225)","0","pure_quanta_power","I71";
;
HDL_POWER"PVDDCR_CPU0_P1"
CDS_LIB"pure_quanta_power";
"A"21;
%"VCC_CORE"
"1","(-3300,8275)","0","pure_quanta_power","I77";
;
HDL_POWER"P3V3_AUX"
CDS_LIB"pure_quanta_power";
"A"42;
%"Q_RES"
"1","(-2900,8150)","0","pure_quanta","I78";
;
LOCATION"R8167"
$SEC"1"
CDS_SEC"1"
MATERIAL"CHIP"
TOLERANCE"1%"
WATTAGE"1/16W"
PACK_TYPE"0402LF"
VALUE"1K"
CDS_LIB"pure_quanta"
PART_NUMBER"CS21002FB06";
"B"
$PN"2"65;
"A"
$PN"1"42;
%"Q_RES"
"1","(-2700,6425)","0","pure_quanta","I79";
;
LOCATION"R8177"
$SEC"1"
CDS_SEC"1"
VALUE"33"
PACK_TYPE"0402LF"
TOLERANCE"5%"
WATTAGE"1/16W"
MATERIAL"CHIP"
CDS_LIB"pure_quanta"
PART_NUMBER"CS03302JB10";
"B"
$PN"2"58;
"A"
$PN"1"100;
%"Q_RES"
"1","(-2700,6575)","0","pure_quanta","I80";
;
LOCATION"R8176"
$SEC"1"
CDS_SEC"1"
PACK_TYPE"0402LF"
WATTAGE"1/16W"
TOLERANCE"5%"
VALUE"0"
MATERIAL"CHIP"
CDS_LIB"pure_quanta"
PART_NUMBER"CS00002JB13";
"B"
$PN"2"60;
"A"
$PN"1"45;
%"Q_RES"
"1","(-2700,6725)","0","pure_quanta","I81";
;
LOCATION"R175"
$SEC"1"
CDS_SEC"1"
PACK_TYPE"0402LF"
WATTAGE"1/16W"
TOLERANCE"5%"
VALUE"0"
MATERIAL"CHIP"
CDS_LIB"pure_quanta"
PART_NUMBER"CS00002JB13";
"B"
$PN"2"49;
"A"
$PN"1"101;
%"Q_RES"
"1","(-2800,6975)","0","pure_quanta","I82";
;
LOCATION"PR172"
$SEC"1"
CDS_SEC"1"
TOLERANCE"5%"
VALUE"0"
PACK_TYPE"0402LF"
WATTAGE"1/16W"
MATERIAL"CHIP"
CDS_LIB"pure_quanta"
PART_NUMBER"CS00002JB13";
"B"
$PN"2"48;
"A"
$PN"1"95;
%"Q_RES"
"1","(-2800,7125)","0","pure_quanta","I83";
;
LOCATION"R8171"
$SEC"1"
CDS_SEC"1"
TOLERANCE"1%"
VALUE"49.9"
MATERIAL"CHIP"
WATTAGE"1/16W"
PACK_TYPE"0402LF"
CDS_LIB"pure_quanta"
PART_NUMBER"CS04992FB07";
"B"
$PN"2"52;
"A"
$PN"1"90;
%"Q_RES"
"1","(-2675,7725)","0","pure_quanta","I84";
;
LOCATION"R8179"
$SEC"1"
CDS_SEC"1"
MATERIAL"CHIP"
PACK_TYPE"0402LF"
VALUE"0"
WATTAGE"1/16W"
TOLERANCE"5%"
CDS_LIB"pure_quanta"
PART_NUMBER"CS00002JB13";
"B"
$PN"2"59;
"A"
$PN"1"91;
%"Q_RES"
"1","(-2675,7875)","0","pure_quanta","I85";
;
LOCATION"R8178"
$SEC"1"
CDS_SEC"1"
PACK_TYPE"0402LF"
WATTAGE"1/16W"
MATERIAL"CHIP"
VALUE"33"
TOLERANCE"5%"
CDS_LIB"pure_quanta"
PART_NUMBER"CS03302JB10";
"B"
$PN"2"65;
"A"
$PN"1"94;
%"Q_CAP"
"2","(-2000,7600)","0","pure_quanta","I86";
;
LOCATION"C249"
$SEC"1"
CDS_SEC"1"
MATERIAL"X7R"
TOLERANCE"5%"
PACK_TYPE"0402"
VALUE"1000PF"
VOLTAGE"50V"
CDS_LIB"pure_quanta"
PART_NUMBER"TMP_QCH21006JB10";
"A"
$PN"1"59;
"B"
$PN"2"43;
%"UNIVERSAL_GND"
"1","(-1775,7525)","0","pure_quanta_power","I87";
;
CDS_LIB"pure_quanta_power"
HDL_POWER"GND";
"A"43;
%"Q_CAP"
"2","(-2025,8150)","0","pure_quanta","I88";
;
LOCATION"C248"
$SEC"1"
CDS_SEC"1"
MATERIAL"EMPTY"
PACK_TYPE"0402"
VOLTAGE"50V"
VALUE"1000PF"
TOLERANCE"5%"
CDS_LIB"pure_quanta"
PART_NUMBER"TMP_QCH21006JB10";
"A"
$PN"1"65;
"B"
$PN"2"44;
%"UNIVERSAL_GND"
"1","(-1775,8075)","0","pure_quanta_power","I89";
;
CDS_LIB"pure_quanta_power"
HDL_POWER"GND";
"A"44;
%"UNIVERSAL_GND"
"1","(-150,2200)","0","pure_quanta_power","I90";
;
CDS_LIB"pure_quanta_power"
HDL_POWER"GND";
"A"22;
%"Q_CAP"
"1","(-150,2475)","0","pure_quanta","I91";
;
LOCATION"PC250"
$SEC"1"
CDS_SEC"1"
MATERIAL"X7R"
VALUE"470PF"
PACK_TYPE"0402"
TOLERANCE"10%"
VOLTAGE"50V"
CDS_LIB"pure_quanta"
PART_NUMBER"TMP_QCH14706KB18";
"B"
$PN"2"22;
"A"
$PN"1"70;
%"UNIVERSAL_GND"
"1","(475,2550)","0","pure_quanta_power","I93";
;
CDS_LIB"pure_quanta_power"
HDL_POWER"GND";
"A"23;
%"Q_CAP"
"1","(475,2800)","0","pure_quanta","I94";
;
LOCATION"PC253"
$SEC"1"
CDS_SEC"1"
MATERIAL"X7R"
TOLERANCE"10%"
VALUE"470PF"
VOLTAGE"50V"
PACK_TYPE"0402"
CDS_LIB"pure_quanta"
PART_NUMBER"TMP_QCH14706KB18";
"B"
$PN"2"23;
"A"
$PN"1"81;
END.
